# T6G (Grand Teton) — schematic netlist excerpt (pin names and nets, part order shuffled) for the footprints in the layout excerpt that follows; sources: Cadence DE-HDL packaged netlist, KiCad conversion of 04192023_DAF0TMB3IC0_F0TG_MB_C_brd_V02_OCP.brd

C1874  Q_CAP  0.1UF 25V 10% X7R  pkg 0402  page 143 : A = P3V3_AUX ; B = GND
PR455  Q_RES  56K 1% CHIP  pkg 0402LF  page 192 : A = PVDD_33_S5_FB ; B = PVDD_33_S5

(kicad_pcb
	(version 20260206)
	(generator "pcbnew")
	(generator_version "10.0")
	(general
		(thickness 1.6)
		(legacy_teardrops no)
	)
	(paper "A4")
	(title_block
		(title "04192023_DAF0TMB3IC0_F0TG_MB_C_brd_V02_OCP.brd")
		(comment 1 "Grand Teton / footprints 1362-1363 of 8354")
	)
	(layers
		(0 "F.Cu" signal "TOP")
		(4 "In1.Cu" signal "GND")
		(6 "In2.Cu" signal "IN1")
		(8 "In3.Cu" signal "GND1")
		(10 "In4.Cu" signal "IN2")
		(12 "In5.Cu" signal "GND2")
		(14 "In6.Cu" signal "IN3")
		(16 "In7.Cu" signal "GND3")
		(18 "In8.Cu" signal "VCC")
		(20 "In9.Cu" signal "VCC1")
		(22 "In10.Cu" signal "GND4")
		(24 "In11.Cu" signal "IN4")
		(26 "In12.Cu" signal "GND5")
		(28 "In13.Cu" signal "IN5")
		(30 "In14.Cu" signal "GND6")
		(32 "In15.Cu" signal "IN6")
		(34 "In16.Cu" signal "GND7")
		(2 "B.Cu" signal "BOTTOM")
		(9 "F.Adhes" user "F.Adhesive")
		(11 "B.Adhes" user "B.Adhesive")
		(13 "F.Paste" user "Package Geometry/Pastemask Top")
		(15 "B.Paste" user "Package Geometry/Pastemask Bottom")
		(5 "F.SilkS" user "Ref Des/Silkscreen Top")
		(7 "B.SilkS" user "Ref Des/Silkscreen Bottom")
		(1 "F.Mask" user "Board Geometry/Soldermask Top")
		(3 "B.Mask" user "Board Geometry/Soldermask Bottom")
		(17 "Dwgs.User" user "User.Drawings")
		(19 "Cmts.User" user "User.Comments")
		(21 "Eco1.User" user "User.Eco1")
		(23 "Eco2.User" user "User.Eco2")
		(25 "Edge.Cuts" user "Board Geometry/Outline")
		(27 "Margin" user)
		(31 "F.CrtYd" user "Package Geometry/Place Bound Top")
		(29 "B.CrtYd" user "Package Geometry/Place Bound Bottom")
		(35 "F.Fab" user "Ref Des/Assembly Top")
		(33 "B.Fab" user "Ref Des/Assembly Bottom")
	)
	(footprint ""
		(layer "F.Cu")
		(at 419.58514 -58.797698 90)
		(property "Reference" "C1874"
			(at 0 0 90)
			(layer "F.SilkS")
			(hide yes)
			(effects
				(font
					(size 1.27 1.27)
				)
			)
		)
		(property "Value" ""
			(at 0 0 90)
			(layer "F.Fab")
			(effects
				(font
					(size 1.27 1.27)
				)
			)
		)
		(duplicate_pad_numbers_are_jumpers no)
		(fp_line
			(start 0.7874 -0.4064)
			(end 0.7874 0.4064)
			(stroke
				(width 0.1524)
				(type default)
			)
			(layer "F.SilkS")
		)
		(fp_line
			(start -0.7874 -0.4064)
			(end 0.7874 -0.4064)
			(stroke
				(width 0.1524)
				(type default)
			)
			(layer "F.SilkS")
		)
		(fp_line
			(start 0.7874 0.4064)
			(end -0.7874 0.4064)
			(stroke
				(width 0.1524)
				(type default)
			)
			(layer "F.SilkS")
		)
		(fp_line
			(start -0.7874 0.4064)
			(end -0.7874 -0.4064)
			(stroke
				(width 0.1524)
				(type default)
			)
			(layer "F.SilkS")
		)
		(fp_line
			(start -0.12065 -0.305054)
			(end -0.12065 -0.2794)
			(stroke
				(width 0.1)
				(type default)
			)
			(layer "F.Fab")
		)
		(fp_line
			(start -0.67945 -0.305054)
			(end -0.12065 -0.305054)
			(stroke
				(width 0.1)
				(type default)
			)
			(layer "F.Fab")
		)
		(fp_line
			(start 0.67945 -0.3048)
			(end 0.67945 0.3048)
			(stroke
				(width 0.1)
				(type default)
			)
			(layer "F.Fab")
		)
		(fp_line
			(start 0.12065 -0.3048)
			(end 0.67945 -0.3048)
			(stroke
				(width 0.1)
				(type default)
			)
			(layer "F.Fab")
		)
		(fp_line
			(start 0.12065 -0.2794)
			(end 0.12065 -0.3048)
			(stroke
				(width 0.1)
				(type default)
			)
			(layer "F.Fab")
		)
		(fp_line
			(start -0.12065 -0.2794)
			(end 0.12065 -0.2794)
			(stroke
				(width 0.1)
				(type default)
			)
			(layer "F.Fab")
		)
		(fp_line
			(start 0.120396 0.2794)
			(end -0.12065 0.2794)
			(stroke
				(width 0.1)
				(type default)
			)
			(layer "F.Fab")
		)
		(fp_line
			(start -0.12065 0.2794)
			(end -0.12065 0.3048)
			(stroke
				(width 0.1)
				(type default)
			)
			(layer "F.Fab")
		)
		(fp_line
			(start 0.67945 0.3048)
			(end 0.120396 0.3048)
			(stroke
				(width 0.1)
				(type default)
			)
			(layer "F.Fab")
		)
		(fp_line
			(start 0.120396 0.3048)
			(end 0.120396 0.2794)
			(stroke
				(width 0.1)
				(type default)
			)
			(layer "F.Fab")
		)
		(fp_line
			(start -0.12065 0.3048)
			(end -0.67945 0.3048)
			(stroke
				(width 0.1)
				(type default)
			)
			(layer "F.Fab")
		)
		(fp_line
			(start -0.67945 0.3048)
			(end -0.67945 -0.305054)
			(stroke
				(width 0.1)
				(type default)
			)
			(layer "F.Fab")
		)
		(pad "1" smd circle
			(at -0.40005 0 90)
			(size 0 0)
			(layers "F.Cu" "F.Mask" "F.Paste")
			(net "P3V3_AUX")
		)
		(pad "2" smd circle
			(at 0.40005 0 90)
			(size 0 0)
			(layers "F.Cu" "F.Mask" "F.Paste")
			(net "GND")
		)
	)
	(footprint ""
		(layer "F.Cu")
		(at 205.365604 -342.075262 -90)
		(property "Reference" "PR455"
			(at 0 0 270)
			(layer "F.SilkS")
			(hide yes)
			(effects
				(font
					(size 1.27 1.27)
				)
			)
		)
		(property "Value" ""
			(at 0 0 270)
			(layer "F.Fab")
			(effects
				(font
					(size 1.27 1.27)
				)
			)
		)
		(duplicate_pad_numbers_are_jumpers no)
		(fp_line
			(start -0.7874 0.4064)
			(end -0.7874 -0.4064)
			(stroke
				(width 0.1524)
				(type default)
			)
			(layer "F.SilkS")
		)
		(fp_line
			(start 0.7874 0.4064)
			(end -0.7874 0.4064)
			(stroke
				(width 0.1524)
				(type default)
			)
			(layer "F.SilkS")
		)
		(fp_line
			(start -0.7874 -0.4064)
			(end 0.7874 -0.4064)
			(stroke
				(width 0.1524)
				(type default)
			)
			(layer "F.SilkS")
		)
		(fp_line
			(start 0.7874 -0.4064)
			(end 0.7874 0.4064)
			(stroke
				(width 0.1524)
				(type default)
			)
			(layer "F.SilkS")
		)
		(fp_line
			(start -0.67945 0.3048)
			(end -0.67945 -0.305054)
			(stroke
				(width 0.1)
				(type default)
			)
			(layer "F.Fab")
		)
		(fp_line
			(start -0.12065 0.3048)
			(end -0.67945 0.3048)
			(stroke
				(width 0.1)
				(type default)
			)
			(layer "F.Fab")
		)
		(fp_line
			(start 0.120396 0.3048)
			(end 0.120396 0.2794)
			(stroke
				(width 0.1)
				(type default)
			)
			(layer "F.Fab")
		)
		(fp_line
			(start 0.67945 0.3048)
			(end 0.120396 0.3048)
			(stroke
				(width 0.1)
				(type default)
			)
			(layer "F.Fab")
		)
		(fp_line
			(start -0.12065 0.2794)
			(end -0.12065 0.3048)
			(stroke
				(width 0.1)
				(type default)
			)
			(layer "F.Fab")
		)
		(fp_line
			(start 0.120396 0.2794)
			(end -0.12065 0.2794)
			(stroke
				(width 0.1)
				(type default)
			)
			(layer "F.Fab")
		)
		(fp_line
			(start -0.12065 -0.2794)
			(end 0.12065 -0.2794)
			(stroke
				(width 0.1)
				(type default)
			)
			(layer "F.Fab")
		)
		(fp_line
			(start 0.12065 -0.2794)
			(end 0.12065 -0.3048)
			(stroke
				(width 0.1)
				(type default)
			)
			(layer "F.Fab")
		)
		(fp_line
			(start 0.12065 -0.3048)
			(end 0.67945 -0.3048)
			(stroke
				(width 0.1)
				(type default)
			)
			(layer "F.Fab")
		)
		(fp_line
			(start 0.67945 -0.3048)
			(end 0.67945 0.3048)
			(stroke
				(width 0.1)
				(type default)
			)
			(layer "F.Fab")
		)
		(fp_line
			(start -0.67945 -0.305054)
			(end -0.12065 -0.305054)
			(stroke
				(width 0.1)
				(type default)
			)
			(layer "F.Fab")
		)
		(fp_line
			(start -0.12065 -0.305054)
			(end -0.12065 -0.2794)
			(stroke
				(width 0.1)
				(type default)
			)
			(layer "F.Fab")
		)
		(pad "1" smd circle
			(at -0.40005 0 270)
			(size 0 0)
			(layers "F.Cu" "F.Mask" "F.Paste")
			(net "PVDD_33_S5_FB")
		)
		(pad "2" smd circle
			(at 0.40005 0 270)
			(size 0 0)
			(layers "F.Cu" "F.Mask" "F.Paste")
			(net "PVDD_33_S5")
		)
	)
)
